FILE_TYPE = CONNECTIVITY;
{Allegro Design Entry HDL 17.4-2019 S026 (4007227) 1/17/2022}
"PAGE_NUMBER" = 266;
0"NC";
1"T1_GND\g";
2"T1_GND\g";
3"T1_GND\g";
4"TDR_DIFF_85_NECK_IN1_DN"CDS_PHYS_NET_NAME"TDR_DIFF_85_NECK_IN1_DN";
5"TDR_DIFF_85_NECK_IN1_DP"CDS_PHYS_NET_NAME"TDR_DIFF_85_NECK_IN1_DP";
6"TDR_DIFF_85_NECK_IN3_DP"CDS_PHYS_NET_NAME"TDR_DIFF_85_NECK_IN3_DP";
7"TDR_DIFF_85_NECK_IN2_DP"CDS_PHYS_NET_NAME"TDR_DIFF_85_NECK_IN2_DP";
8"TDR_DIFF_85_NECK_IN2_DN"CDS_PHYS_NET_NAME"TDR_DIFF_85_NECK_IN2_DN";
9"TDR_DIFF_85_NECK_IN3_DN"CDS_PHYS_NET_NAME"TDR_DIFF_85_NECK_IN3_DN";
10"T1_GND\g";
11"T1_GND\g";
12"T1_GND\g";
13"T1_GND\g";
14"T1_GND\g";
15"T1_GND\g";
16"TDR_DIFF_85_NECK_IN4_DP"CDS_PHYS_NET_NAME"TDR_DIFF_85_NECK_IN4_DP";
17"TDR_DIFF_85_NECK_IN4_DN"CDS_PHYS_NET_NAME"TDR_DIFF_85_NECK_IN4_DN";
18"TDR_DIFF_85_NECK_IN5_DP"CDS_PHYS_NET_NAME"TDR_DIFF_85_NECK_IN5_DP";
19"TDR_DIFF_85_NECK_IN5_DN"CDS_PHYS_NET_NAME"TDR_DIFF_85_NECK_IN5_DN";
20"TDR_DIFF_85_NECK_IN6_DN"CDS_PHYS_NET_NAME"TDR_DIFF_85_NECK_IN6_DN";
21"TDR_DIFF_85_NECK_IN6_DP"CDS_PHYS_NET_NAME"TDR_DIFF_85_NECK_IN6_DP";
22"T1_GND\g";
23"T1_GND\g";
24"T1_GND\g";
%"UNIVERSAL_GND"
"1","(-7425,1775)","0","pure_quanta_power","I1";
;
HDL_POWER"T1_GND"
CDS_LIB"pure_quanta_power";
"A"24;
%"TP_TDR_4P_FTS"
"1","(-7000,5000)","0","pure_quanta","I10";
;
LOCATION"X9003"
$SEC"1"
CDS_SEC"1"
PACK_TYPE"TH"
MATERIAL"EMPTY"
VALUE"TP_TDR_4P_DIP"
NEEDS_NO_SIZE"TRUE"
CDS_LIB"pure_quanta"
PART_NUMBER"TP15";
"S1"
$PN"1"7;
"P2 \B"
$PN"3"11;
"S2"
$PN"4"8;
"P1 \B"
$PN"2"11;
%"UNIVERSAL_GND"
"1","(-7425,5550)","0","pure_quanta_power","I11";
;
HDL_POWER"T1_GND"
CDS_LIB"pure_quanta_power";
"A"10;
%"TP_TDR_4P_FTS"
"1","(-7000,5775)","0","pure_quanta","I12";
;
LOCATION"X9002"
$SEC"1"
CDS_SEC"1"
PACK_TYPE"TH"
MATERIAL"EMPTY"
VALUE"TP_TDR_4P_DIP"
CDS_LIB"pure_quanta"
NEEDS_NO_SIZE"TRUE"
PART_NUMBER"TP15";
"S1"
$PN"1"5;
"P2 \B"
$PN"3"10;
"S2"
$PN"4"4;
"P1 \B"
$PN"2"10;
%"TP_TDR_4P_FTS"
"1","(-5675,2000)","4","pure_quanta","I13";
;
LOCATION"X9028"
$SEC"1"
CDS_SEC"1"
PACK_TYPE"TH"
MATERIAL"EMPTY"
VALUE"TP_TDR_4P_DIP"
NEEDS_NO_SIZE"TRUE"
CDS_LIB"pure_quanta"
PART_NUMBER"TP15";
"S1"
$PN"1"20;
"P2 \B"
$PN"3"15;
"S2"
$PN"4"21;
"P1 \B"
$PN"2"15;
%"UNIVERSAL_GND"
"1","(-5275,1775)","0","pure_quanta_power","I14";
;
HDL_POWER"T1_GND"
CDS_LIB"pure_quanta_power";
"A"15;
%"TP_TDR_4P_FTS"
"1","(-5675,2775)","4","pure_quanta","I15";
;
LOCATION"X9027"
$SEC"1"
CDS_SEC"1"
PACK_TYPE"TH"
VALUE"TP_TDR_4P_DIP"
MATERIAL"EMPTY"
NEEDS_NO_SIZE"TRUE"
CDS_LIB"pure_quanta"
PART_NUMBER"TP15";
"S1"
$PN"1"19;
"P2 \B"
$PN"3"14;
"S2"
$PN"4"18;
"P1 \B"
$PN"2"14;
%"TP_TDR_4P_FTS"
"1","(-5675,4225)","4","pure_quanta","I16";
;
LOCATION"X9010"
$SEC"1"
CDS_SEC"1"
PACK_TYPE"TH"
VALUE"TP_TDR_4P_DIP"
MATERIAL"EMPTY"
NEEDS_NO_SIZE"TRUE"
CDS_LIB"pure_quanta"
PART_NUMBER"TP15";
"S1"
$PN"1"9;
"P2 \B"
$PN"3"3;
"S2"
$PN"4"6;
"P1 \B"
$PN"2"3;
%"TP_TDR_4P_FTS"
"1","(-5675,3450)","4","pure_quanta","I17";
;
LOCATION"X9011"
$SEC"1"
CDS_SEC"1"
PACK_TYPE"TH"
MATERIAL"EMPTY"
VALUE"TP_TDR_4P_DIP"
NEEDS_NO_SIZE"TRUE"
CDS_LIB"pure_quanta"
PART_NUMBER"TP15";
"S1"
$PN"1"17;
"P2 \B"
$PN"3"13;
"S2"
$PN"4"16;
"P1 \B"
$PN"2"13;
%"UNIVERSAL_GND"
"1","(-5275,2550)","0","pure_quanta_power","I18";
;
HDL_POWER"T1_GND"
CDS_LIB"pure_quanta_power";
"A"14;
%"UNIVERSAL_GND"
"1","(-5275,4000)","0","pure_quanta_power","I19";
;
HDL_POWER"T1_GND"
CDS_LIB"pure_quanta_power";
"A"3;
%"TP_TDR_4P_FTS"
"1","(-7000,2000)","0","pure_quanta","I2";
;
LOCATION"X9026"
$SEC"1"
CDS_SEC"1"
MATERIAL"EMPTY"
PACK_TYPE"TH"
VALUE"TP_TDR_4P_DIP"
NEEDS_NO_SIZE"TRUE"
CDS_LIB"pure_quanta"
PART_NUMBER"TP15";
"S1"
$PN"1"21;
"P2 \B"
$PN"3"24;
"S2"
$PN"4"20;
"P1 \B"
$PN"2"24;
%"UNIVERSAL_GND"
"1","(-5275,3225)","0","pure_quanta_power","I20";
;
HDL_POWER"T1_GND"
CDS_LIB"pure_quanta_power";
"A"13;
%"UNIVERSAL_GND"
"1","(-7425,2550)","0","pure_quanta_power","I3";
;
HDL_POWER"T1_GND"
CDS_LIB"pure_quanta_power";
"A"23;
%"TP_TDR_4P_FTS"
"1","(-5675,5000)","4","pure_quanta","I37";
;
LOCATION"X9009"
$SEC"1"
CDS_SEC"1"
PACK_TYPE"TH"
MATERIAL"EMPTY"
VALUE"TP_TDR_4P_DIP"
NEEDS_NO_SIZE"TRUE"
CDS_LIB"pure_quanta"
PART_NUMBER"TP15";
"S1"
$PN"1"8;
"P2 \B"
$PN"3"2;
"S2"
$PN"4"7;
"P1 \B"
$PN"2"2;
%"TP_TDR_4P_FTS"
"1","(-5675,5775)","4","pure_quanta","I38";
;
LOCATION"X9008"
$SEC"1"
CDS_SEC"1"
PACK_TYPE"TH"
MATERIAL"EMPTY"
VALUE"TP_TDR_4P_DIP"
CDS_LIB"pure_quanta"
NEEDS_NO_SIZE"TRUE"
PART_NUMBER"TP15";
"S1"
$PN"1"4;
"P2 \B"
$PN"3"1;
"S2"
$PN"4"5;
"P1 \B"
$PN"2"1;
%"UNIVERSAL_GND"
"1","(-5275,4775)","0","pure_quanta_power","I39";
;
HDL_POWER"T1_GND"
CDS_LIB"pure_quanta_power";
"A"2;
%"TP_TDR_4P_FTS"
"1","(-7000,2775)","0","pure_quanta","I4";
;
LOCATION"X9025"
$SEC"1"
CDS_SEC"1"
MATERIAL"EMPTY"
PACK_TYPE"TH"
VALUE"TP_TDR_4P_DIP"
NEEDS_NO_SIZE"TRUE"
CDS_LIB"pure_quanta"
PART_NUMBER"TP15";
"S1"
$PN"1"18;
"P2 \B"
$PN"3"23;
"S2"
$PN"4"19;
"P1 \B"
$PN"2"23;
%"UNIVERSAL_GND"
"1","(-5275,5550)","0","pure_quanta_power","I40";
;
HDL_POWER"T1_GND"
CDS_LIB"pure_quanta_power";
"A"1;
%"UNIVERSAL_GND"
"1","(-7425,3225)","0","pure_quanta_power","I5";
;
HDL_POWER"T1_GND"
CDS_LIB"pure_quanta_power";
"A"22;
%"UNIVERSAL_GND"
"1","(-7425,4000)","0","pure_quanta_power","I6";
;
HDL_POWER"T1_GND"
CDS_LIB"pure_quanta_power";
"A"12;
%"TP_TDR_4P_FTS"
"1","(-7000,3450)","0","pure_quanta","I7";
;
LOCATION"X9005"
$SEC"1"
CDS_SEC"1"
MATERIAL"EMPTY"
PACK_TYPE"TH"
VALUE"TP_TDR_4P_DIP"
NEEDS_NO_SIZE"TRUE"
CDS_LIB"pure_quanta"
PART_NUMBER"TP15";
"S1"
$PN"1"16;
"P2 \B"
$PN"3"22;
"S2"
$PN"4"17;
"P1 \B"
$PN"2"22;
%"TP_TDR_4P_FTS"
"1","(-7000,4225)","0","pure_quanta","I8";
;
LOCATION"X9004"
$SEC"1"
CDS_SEC"1"
MATERIAL"EMPTY"
PACK_TYPE"TH"
VALUE"TP_TDR_4P_DIP"
NEEDS_NO_SIZE"TRUE"
CDS_LIB"pure_quanta"
PART_NUMBER"TP15";
"S1"
$PN"1"6;
"P2 \B"
$PN"3"12;
"S2"
$PN"4"9;
"P1 \B"
$PN"2"12;
%"UNIVERSAL_GND"
"1","(-7425,4775)","0","pure_quanta_power","I9";
;
HDL_POWER"T1_GND"
CDS_LIB"pure_quanta_power";
"A"11;
END.
